(kicad_pcb
	(version 20211014)
	(generator pcbnew)
	(general
    (thickness 1.6)
  )
	(paper "A4")
	(title_block
    (title "SI test board")
    (rev "1.0.1")
    (company "Antmicro")
		(comment 9 "footprints 13-18 of 27")
	)
	(layers
    (0 "F.Cu" signal)
    (1 "In1.Cu" signal)
    (2 "In2.Cu" signal)
    (31 "B.Cu" signal)
    (32 "B.Adhes" user "B.Adhesive")
    (33 "F.Adhes" user "F.Adhesive")
    (34 "B.Paste" user)
    (35 "F.Paste" user)
    (36 "B.SilkS" user "B.Silkscreen")
    (37 "F.SilkS" user "F.Silkscreen")
    (38 "B.Mask" user)
    (39 "F.Mask" user)
    (40 "Dwgs.User" user "User.Drawings")
    (41 "Cmts.User" user "User.Comments")
    (42 "Eco1.User" user "User.Eco1")
    (43 "Eco2.User" user "User.Eco2")
    (44 "Edge.Cuts" user)
    (45 "Margin" user)
    (46 "B.CrtYd" user "B.Courtyard")
    (47 "F.CrtYd" user "F.Courtyard")
    (48 "B.Fab" user)
    (49 "F.Fab" user)
  )
	(footprint "si-simulation-test-board-footprints:RF_SMA_BoardEdge_RF2-143-T-17-50-G" (layer "F.Cu")
    (tedit 64FEFFC5)
    (at 146.68 106.0005 -90)
    (descr "RF SMA SMD board edge connector")
    (property "Author" "Antmicro")
    (property "License" "Apache-2.0")
    (property "MPN" "RF2-143-T-17-50-G")
    (property "Manufacturer" "ADAM TECH")
    (property "Sheetfile" "si-simulation-test-board.kicad_sch")
    (property "Sheetname" "")
    (attr smd)
    (fp_text reference "J13" (at -4.5 6.88) (layer "F.SilkS")
      (effects (font (size 0.7 0.7) (thickness 0.15)) (justify left bottom))
    )
    (fp_text value "Conn_SMA_RF2-143-T-17-50-G" (at 0 9.24 -90) (layer "F.Fab")
      (effects (font (size 0.7 0.7) (thickness 0.15)) (justify left bottom))
    )
    (fp_text user "${REFERENCE}" (at -4.5 13.64 -90) (layer "F.Fab") hide
      (effects (font (size 0.7 0.7) (thickness 0.15)) (justify left bottom))
    )
    (fp_text user "Author: Antmicro" (at -4.5 11.24 -90) (layer "F.Fab") hide
      (effects (font (size 0.7 0.7) (thickness 0.15)) (justify left bottom))
    )
    (fp_text user "License: Apache-2.0" (at -4.5 12.44 -90) (layer "F.Fab") hide
      (effects (font (size 0.7 0.7) (thickness 0.15)) (justify left bottom))
    )
    (fp_rect (start -3.995 -7.53) (end 3.995 7.53) (layer "B.CrtYd") (width 0.05) (fill none))
    (fp_rect (start -3.995 -7.53) (end 3.995 7.53) (layer "F.CrtYd") (width 0.05) (fill none))
    (fp_line (start 3.174 1.504) (end -3.174 1.504) (layer "F.Fab") (width 0.15))
    (fp_line (start -3.174 6.455) (end -3.174 1.504) (layer "F.Fab") (width 0.15))
    (fp_line (start 2.65 -6.375) (end -2.65 -6.375) (layer "F.Fab") (width 0.15))
    (fp_line (start 3.174 6.455) (end 3.174 1.504) (layer "F.Fab") (width 0.15))
    (fp_line (start 0.375 6.455) (end -0.38 6.455) (layer "F.Fab") (width 0.15))
    (fp_line (start -2.375 2.678) (end -2.375 6.455) (layer "F.Fab") (width 0.15))
    (fp_line (start 2.65 -6.375) (end 2.65 1.504) (layer "F.Fab") (width 0.15))
    (fp_line (start 2.375 6.455) (end 2.375 2.678) (layer "F.Fab") (width 0.15))
    (fp_line (start -2.65 -6.375) (end -2.65 1.504) (layer "F.Fab") (width 0.15))
    (fp_line (start -0.38 2.654) (end -0.38 6.455) (layer "F.Fab") (width 0.15))
    (fp_line (start 3.174 2.654) (end -3.15 2.654) (layer "F.Fab") (width 0.15))
    (fp_line (start 0.38 2.654) (end 0.375 6.455) (layer "F.Fab") (width 0.15))
    (fp_line (start -2.375 6.455) (end -3.174 6.455) (layer "F.Fab") (width 0.15))
    (fp_line (start 3.174 6.455) (end 2.375 6.455) (layer "F.Fab") (width 0.15))
    (pad "1" smd rect (at 0.007 4.955 270) (size 2.29 4.191) (layers "F.Cu" "F.Paste" "F.Mask")
      (net 7 "/DIFF_P") (pinfunction "1") (pintype "passive"))
    (pad "2" smd rect (at -2.975 4.955 270) (size 1.45 4.191) (layers "B.Cu" "B.Paste" "B.Mask")
      (net 2 "GND") (pinfunction "2") (pintype "passive"))
    (pad "2" smd rect (at 2.975 4.955 270) (size 1.45 4.191) (layers "B.Cu" "B.Paste" "B.Mask")
      (net 2 "GND") (pinfunction "2") (pintype "passive"))
    (pad "2" smd rect (at -2.975 4.955 270) (size 1.45 4.191) (layers "F.Cu" "F.Paste" "F.Mask")
      (net 2 "GND") (pinfunction "2") (pintype "passive"))
    (pad "2" smd rect (at 2.975 4.955 270) (size 1.45 4.191) (layers "F.Cu" "F.Paste" "F.Mask")
      (net 2 "GND") (pinfunction "2") (pintype "passive"))
  )
	(footprint "si-simulation-test-board-footprints:RF_SMA_BoardEdge_RF2-143-T-17-50-G" (layer "F.Cu")
    (tedit 64FEFFC5)
    (at 91.37 137.614499 90)
    (descr "RF SMA SMD board edge connector")
    (property "Author" "Antmicro")
    (property "License" "Apache-2.0")
    (property "MPN" "RF2-143-T-17-50-G")
    (property "Manufacturer" "ADAM TECH")
    (property "Sheetfile" "si-simulation-test-board.kicad_sch")
    (property "Sheetname" "")
    (attr smd)
    (fp_text reference "J15" (at -4.5 6.88 180) (layer "F.SilkS")
      (effects (font (size 0.7 0.7) (thickness 0.15)) (justify left bottom))
    )
    (fp_text value "Conn_SMA_RF2-143-T-17-50-G" (at 0 9.24 90) (layer "F.Fab")
      (effects (font (size 0.7 0.7) (thickness 0.15)) (justify left bottom))
    )
    (fp_text user "License: Apache-2.0" (at -4.5 12.44 90) (layer "F.Fab") hide
      (effects (font (size 0.7 0.7) (thickness 0.15)) (justify left bottom))
    )
    (fp_text user "Author: Antmicro" (at -4.5 11.24 90) (layer "F.Fab") hide
      (effects (font (size 0.7 0.7) (thickness 0.15)) (justify left bottom))
    )
    (fp_text user "${REFERENCE}" (at -4.5 13.64 90) (layer "F.Fab") hide
      (effects (font (size 0.7 0.7) (thickness 0.15)) (justify left bottom))
    )
    (fp_rect (start -3.995 -7.53) (end 3.995 7.53) (layer "B.CrtYd") (width 0.05) (fill none))
    (fp_rect (start -3.995 -7.53) (end 3.995 7.53) (layer "F.CrtYd") (width 0.05) (fill none))
    (fp_line (start 3.174 6.455) (end 3.174 1.504) (layer "F.Fab") (width 0.15))
    (fp_line (start 3.174 6.455) (end 2.375 6.455) (layer "F.Fab") (width 0.15))
    (fp_line (start -2.375 6.455) (end -3.174 6.455) (layer "F.Fab") (width 0.15))
    (fp_line (start 3.174 1.504) (end -3.174 1.504) (layer "F.Fab") (width 0.15))
    (fp_line (start 3.174 2.654) (end -3.15 2.654) (layer "F.Fab") (width 0.15))
    (fp_line (start -2.65 -6.375) (end -2.65 1.504) (layer "F.Fab") (width 0.15))
    (fp_line (start -2.375 2.678) (end -2.375 6.455) (layer "F.Fab") (width 0.15))
    (fp_line (start 2.375 6.455) (end 2.375 2.678) (layer "F.Fab") (width 0.15))
    (fp_line (start 2.65 -6.375) (end -2.65 -6.375) (layer "F.Fab") (width 0.15))
    (fp_line (start 0.38 2.654) (end 0.375 6.455) (layer "F.Fab") (width 0.15))
    (fp_line (start -0.38 2.654) (end -0.38 6.455) (layer "F.Fab") (width 0.15))
    (fp_line (start 0.375 6.455) (end -0.38 6.455) (layer "F.Fab") (width 0.15))
    (fp_line (start -3.174 6.455) (end -3.174 1.504) (layer "F.Fab") (width 0.15))
    (fp_line (start 2.65 -6.375) (end 2.65 1.504) (layer "F.Fab") (width 0.15))
    (pad "1" smd rect (at 0.007 4.955 90) (size 2.29 4.191) (layers "F.Cu" "F.Paste" "F.Mask")
      (net 9 "Net-(J15-Pad1)") (pinfunction "1") (pintype "passive"))
    (pad "2" smd rect (at -2.975 4.955 90) (size 1.45 4.191) (layers "F.Cu" "F.Paste" "F.Mask")
      (net 2 "GND") (pinfunction "2") (pintype "passive"))
    (pad "2" smd rect (at 2.975 4.955 90) (size 1.45 4.191) (layers "B.Cu" "B.Paste" "B.Mask")
      (net 2 "GND") (pinfunction "2") (pintype "passive"))
    (pad "2" smd rect (at -2.975 4.955 90) (size 1.45 4.191) (layers "B.Cu" "B.Paste" "B.Mask")
      (net 2 "GND") (pinfunction "2") (pintype "passive"))
    (pad "2" smd rect (at 2.975 4.955 90) (size 1.45 4.191) (layers "F.Cu" "F.Paste" "F.Mask")
      (net 2 "GND") (pinfunction "2") (pintype "passive"))
  )
	(footprint "si-simulation-test-board-footprints:R_0201" (layer "F.Cu")
    (tedit 5FBD1D44)
    (at 116.144 99.100001 180)
    (descr "Resistor SMD 0201")
    (tags "resistor SMD 0201")
    (property "Author" "Antmicro")
    (property "DNP" "DNP")
    (property "License" "Apache-2.0")
    (property "MPN" "CR0201-FX-0R00GLF")
    (property "Manufacturer" "Bourns")
    (property "Sheetfile" "si-simulation-test-board.kicad_sch")
    (property "Sheetname" "")
    (property "Tolerance" "1%")
    (property "Val" "0R")
    (attr smd)
    (fp_text reference "R4" (at 0 -0.5) (layer "F.SilkS") hide
      (effects (font (size 0.7 0.7) (thickness 0.15)) (justify right bottom))
    )
    (fp_text value "R_0R_0201" (at 0 1.25) (layer "F.Fab")
      (effects (font (size 0.7 0.7) (thickness 0.15)) (justify right bottom))
    )
    (fp_text user "Author: Antmicro" (at -0.71 5.25) (layer "F.Fab") hide
      (effects (font (size 0.7 0.7) (thickness 0.15)) (justify right bottom))
    )
    (fp_text user "${REFERENCE}" (at -0.71 3.25) (layer "F.Fab") hide
      (effects (font (size 0.7 0.7) (thickness 0.15)) (justify right bottom))
    )
    (fp_text user "License: Apache-2.0" (at -0.71 4.25) (layer "F.Fab") hide
      (effects (font (size 0.7 0.7) (thickness 0.15)) (justify right bottom))
    )
    (fp_rect (start -0.71 -0.36) (end 0.71 0.36) (layer "F.CrtYd") (width 0.05) (fill none))
    (fp_rect (start -0.3 -0.15) (end 0.298 0.148) (layer "F.Fab") (width 0.15) (fill none))
    (pad "" smd roundrect (at -0.346 0 180) (size 0.318 0.36) (layers "F.Paste") (roundrect_rratio 0.25))
    (pad "" smd roundrect (at 0.344 0 180) (size 0.318 0.36) (layers "F.Paste") (roundrect_rratio 0.25))
    (pad "1" smd roundrect (at -0.32 0 180) (size 0.46 0.4) (layers "F.Cu" "F.Mask") (roundrect_rratio 0.25)
      (net 2 "GND") (pintype "passive"))
    (pad "2" smd roundrect (at 0.32 0 180) (size 0.46 0.4) (layers "F.Cu" "F.Mask") (roundrect_rratio 0.25)
      (net 6 "Net-(J10-Pad1)") (pintype "passive"))
  )
	(footprint "si-simulation-test-board-footprints:RF_SMA_BoardEdge_RF2-143-T-17-50-G" (layer "F.Cu")
    (tedit 64FEFFC5)
    (at 91.32 75.999499 90)
    (descr "RF SMA SMD board edge connector")
    (property "Author" "Antmicro")
    (property "License" "Apache-2.0")
    (property "MPN" "RF2-143-T-17-50-G")
    (property "Manufacturer" "ADAM TECH")
    (property "Sheetfile" "si-simulation-test-board.kicad_sch")
    (property "Sheetname" "")
    (attr smd)
    (fp_text reference "J1" (at -4.5 6.88 180) (layer "F.SilkS")
      (effects (font (size 0.7 0.7) (thickness 0.15)) (justify left bottom))
    )
    (fp_text value "Conn_SMA_RF2-143-T-17-50-G" (at 0 9.24 90) (layer "F.Fab")
      (effects (font (size 0.7 0.7) (thickness 0.15)) (justify left bottom))
    )
    (fp_text user "${REFERENCE}" (at -4.5 13.64 90) (layer "F.Fab") hide
      (effects (font (size 0.7 0.7) (thickness 0.15)) (justify left bottom))
    )
    (fp_text user "Author: Antmicro" (at -4.5 11.24 90) (layer "F.Fab") hide
      (effects (font (size 0.7 0.7) (thickness 0.15)) (justify left bottom))
    )
    (fp_text user "License: Apache-2.0" (at -4.5 12.44 90) (layer "F.Fab") hide
      (effects (font (size 0.7 0.7) (thickness 0.15)) (justify left bottom))
    )
    (fp_rect (start -3.995 -7.53) (end 3.995 7.53) (layer "B.CrtYd") (width 0.05) (fill none))
    (fp_rect (start -3.995 -7.53) (end 3.995 7.53) (layer "F.CrtYd") (width 0.05) (fill none))
    (fp_line (start -2.375 2.678) (end -2.375 6.455) (layer "F.Fab") (width 0.15))
    (fp_line (start 2.65 -6.375) (end 2.65 1.504) (layer "F.Fab") (width 0.15))
    (fp_line (start -0.38 2.654) (end -0.38 6.455) (layer "F.Fab") (width 0.15))
    (fp_line (start 3.174 6.455) (end 2.375 6.455) (layer "F.Fab") (width 0.15))
    (fp_line (start 3.174 1.504) (end -3.174 1.504) (layer "F.Fab") (width 0.15))
    (fp_line (start -2.65 -6.375) (end -2.65 1.504) (layer "F.Fab") (width 0.15))
    (fp_line (start -3.174 6.455) (end -3.174 1.504) (layer "F.Fab") (width 0.15))
    (fp_line (start 3.174 2.654) (end -3.15 2.654) (layer "F.Fab") (width 0.15))
    (fp_line (start 2.65 -6.375) (end -2.65 -6.375) (layer "F.Fab") (width 0.15))
    (fp_line (start 0.375 6.455) (end -0.38 6.455) (layer "F.Fab") (width 0.15))
    (fp_line (start 3.174 6.455) (end 3.174 1.504) (layer "F.Fab") (width 0.15))
    (fp_line (start 0.38 2.654) (end 0.375 6.455) (layer "F.Fab") (width 0.15))
    (fp_line (start -2.375 6.455) (end -3.174 6.455) (layer "F.Fab") (width 0.15))
    (fp_line (start 2.375 6.455) (end 2.375 2.678) (layer "F.Fab") (width 0.15))
    (pad "1" smd rect (at 0.007 4.955 90) (size 2.29 4.191) (layers "F.Cu" "F.Paste" "F.Mask")
      (net 1 "Net-(J1-Pad1)") (pinfunction "1") (pintype "passive"))
    (pad "2" smd rect (at -2.975 4.955 90) (size 1.45 4.191) (layers "B.Cu" "B.Paste" "B.Mask")
      (net 2 "GND") (pinfunction "2") (pintype "passive"))
    (pad "2" smd rect (at -2.975 4.955 90) (size 1.45 4.191) (layers "F.Cu" "F.Paste" "F.Mask")
      (net 2 "GND") (pinfunction "2") (pintype "passive"))
    (pad "2" smd rect (at 2.975 4.955 90) (size 1.45 4.191) (layers "B.Cu" "B.Paste" "B.Mask")
      (net 2 "GND") (pinfunction "2") (pintype "passive"))
    (pad "2" smd rect (at 2.975 4.955 90) (size 1.45 4.191) (layers "F.Cu" "F.Paste" "F.Mask")
      (net 2 "GND") (pinfunction "2") (pintype "passive"))
  )
	(footprint "si-simulation-test-board-footprints:RF_SMA_BoardEdge_RF2-143-T-17-50-G" (layer "F.Cu")
    (tedit 64FEFFC5)
    (at 146.63 76.0005 -90)
    (descr "RF SMA SMD board edge connector")
    (property "Author" "Antmicro")
    (property "License" "Apache-2.0")
    (property "MPN" "RF2-143-T-17-50-G")
    (property "Manufacturer" "ADAM TECH")
    (property "Sheetfile" "si-simulation-test-board.kicad_sch")
    (property "Sheetname" "")
    (attr smd)
    (fp_text reference "J2" (at -4.5 6.88) (layer "F.SilkS")
      (effects (font (size 0.7 0.7) (thickness 0.15)) (justify left bottom))
    )
    (fp_text value "Conn_SMA_RF2-143-T-17-50-G" (at 0 9.24 -90) (layer "F.Fab")
      (effects (font (size 0.7 0.7) (thickness 0.15)) (justify left bottom))
    )
    (fp_text user "License: Apache-2.0" (at -4.5 12.44 -90) (layer "F.Fab") hide
      (effects (font (size 0.7 0.7) (thickness 0.15)) (justify left bottom))
    )
    (fp_text user "Author: Antmicro" (at -4.5 11.24 -90) (layer "F.Fab") hide
      (effects (font (size 0.7 0.7) (thickness 0.15)) (justify left bottom))
    )
    (fp_text user "${REFERENCE}" (at -4.5 13.64 -90) (layer "F.Fab") hide
      (effects (font (size 0.7 0.7) (thickness 0.15)) (justify left bottom))
    )
    (fp_rect (start -3.995 -7.53) (end 3.995 7.53) (layer "B.CrtYd") (width 0.05) (fill none))
    (fp_rect (start -3.995 -7.53) (end 3.995 7.53) (layer "F.CrtYd") (width 0.05) (fill none))
    (fp_line (start 0.375 6.455) (end -0.38 6.455) (layer "F.Fab") (width 0.15))
    (fp_line (start -2.65 -6.375) (end -2.65 1.504) (layer "F.Fab") (width 0.15))
    (fp_line (start 2.65 -6.375) (end 2.65 1.504) (layer "F.Fab") (width 0.15))
    (fp_line (start 2.375 6.455) (end 2.375 2.678) (layer "F.Fab") (width 0.15))
    (fp_line (start 0.38 2.654) (end 0.375 6.455) (layer "F.Fab") (width 0.15))
    (fp_line (start 3.174 6.455) (end 3.174 1.504) (layer "F.Fab") (width 0.15))
    (fp_line (start -2.375 6.455) (end -3.174 6.455) (layer "F.Fab") (width 0.15))
    (fp_line (start 3.174 2.654) (end -3.15 2.654) (layer "F.Fab") (width 0.15))
    (fp_line (start -0.38 2.654) (end -0.38 6.455) (layer "F.Fab") (width 0.15))
    (fp_line (start -2.375 2.678) (end -2.375 6.455) (layer "F.Fab") (width 0.15))
    (fp_line (start 3.174 1.504) (end -3.174 1.504) (layer "F.Fab") (width 0.15))
    (fp_line (start 3.174 6.455) (end 2.375 6.455) (layer "F.Fab") (width 0.15))
    (fp_line (start 2.65 -6.375) (end -2.65 -6.375) (layer "F.Fab") (width 0.15))
    (fp_line (start -3.174 6.455) (end -3.174 1.504) (layer "F.Fab") (width 0.15))
    (pad "1" smd rect (at 0.007 4.955 270) (size 2.29 4.191) (layers "F.Cu" "F.Paste" "F.Mask")
      (net 1 "Net-(J1-Pad1)") (pinfunction "1") (pintype "passive"))
    (pad "2" smd rect (at -2.975 4.955 270) (size 1.45 4.191) (layers "F.Cu" "F.Paste" "F.Mask")
      (net 2 "GND") (pinfunction "2") (pintype "passive"))
    (pad "2" smd rect (at -2.975 4.955 270) (size 1.45 4.191) (layers "B.Cu" "B.Paste" "B.Mask")
      (net 2 "GND") (pinfunction "2") (pintype "passive"))
    (pad "2" smd rect (at 2.975 4.955 270) (size 1.45 4.191) (layers "B.Cu" "B.Paste" "B.Mask")
      (net 2 "GND") (pinfunction "2") (pintype "passive"))
    (pad "2" smd rect (at 2.975 4.955 270) (size 1.45 4.191) (layers "F.Cu" "F.Paste" "F.Mask")
      (net 2 "GND") (pinfunction "2") (pintype "passive"))
  )
	(footprint "si-simulation-test-board-footprints:RF_SMA_BoardEdge_RF2-143-T-17-50-G" (layer "F.Cu")
    (tedit 64FEFFC5)
    (at 91.37 117.299499 90)
    (descr "RF SMA SMD board edge connector")
    (property "Author" "Antmicro")
    (property "License" "Apache-2.0")
    (property "MPN" "RF2-143-T-17-50-G")
    (property "Manufacturer" "ADAM TECH")
    (property "Sheetfile" "si-simulation-test-board.kicad_sch")
    (property "Sheetname" "")
    (attr smd)
    (fp_text reference "J12" (at -4.5 6.88 180) (layer "F.SilkS")
      (effects (font (size 0.7 0.7) (thickness 0.15)) (justify left bottom))
    )
    (fp_text value "Conn_SMA_RF2-143-T-17-50-G" (at 0 9.24 90) (layer "F.Fab")
      (effects (font (size 0.7 0.7) (thickness 0.15)) (justify left bottom))
    )
    (fp_text user "${REFERENCE}" (at -4.5 13.64 90) (layer "F.Fab") hide
      (effects (font (size 0.7 0.7) (thickness 0.15)) (justify left bottom))
    )
    (fp_text user "License: Apache-2.0" (at -4.5 12.44 90) (layer "F.Fab") hide
      (effects (font (size 0.7 0.7) (thickness 0.15)) (justify left bottom))
    )
    (fp_text user "Author: Antmicro" (at -4.5 11.24 90) (layer "F.Fab") hide
      (effects (font (size 0.7 0.7) (thickness 0.15)) (justify left bottom))
    )
    (fp_rect (start -3.995 -7.53) (end 3.995 7.53) (layer "B.CrtYd") (width 0.05) (fill none))
    (fp_rect (start -3.995 -7.53) (end 3.995 7.53) (layer "F.CrtYd") (width 0.05) (fill none))
    (fp_line (start -3.174 6.455) (end -3.174 1.504) (layer "F.Fab") (width 0.15))
    (fp_line (start 3.174 2.654) (end -3.15 2.654) (layer "F.Fab") (width 0.15))
    (fp_line (start 2.65 -6.375) (end -2.65 -6.375) (layer "F.Fab") (width 0.15))
    (fp_line (start -2.65 -6.375) (end -2.65 1.504) (layer "F.Fab") (width 0.15))
    (fp_line (start -2.375 2.678) (end -2.375 6.455) (layer "F.Fab") (width 0.15))
    (fp_line (start -2.375 6.455) (end -3.174 6.455) (layer "F.Fab") (width 0.15))
    (fp_line (start 2.65 -6.375) (end 2.65 1.504) (layer "F.Fab") (width 0.15))
    (fp_line (start 2.375 6.455) (end 2.375 2.678) (layer "F.Fab") (width 0.15))
    (fp_line (start -0.38 2.654) (end -0.38 6.455) (layer "F.Fab") (width 0.15))
    (fp_line (start 3.174 6.455) (end 2.375 6.455) (layer "F.Fab") (width 0.15))
    (fp_line (start 3.174 1.504) (end -3.174 1.504) (layer "F.Fab") (width 0.15))
    (fp_line (start 3.174 6.455) (end 3.174 1.504) (layer "F.Fab") (width 0.15))
    (fp_line (start 0.375 6.455) (end -0.38 6.455) (layer "F.Fab") (width 0.15))
    (fp_line (start 0.38 2.654) (end 0.375 6.455) (layer "F.Fab") (width 0.15))
    (pad "1" smd rect (at 0.007 4.955 90) (size 2.29 4.191) (layers "F.Cu" "F.Paste" "F.Mask")
      (net 8 "/DIFF_N") (pinfunction "1") (pintype "passive"))
    (pad "2" smd rect (at -2.975 4.955 90) (size 1.45 4.191) (layers "B.Cu" "B.Paste" "B.Mask")
      (net 2 "GND") (pinfunction "2") (pintype "passive"))
    (pad "2" smd rect (at 2.975 4.955 90) (size 1.45 4.191) (layers "F.Cu" "F.Paste" "F.Mask")
      (net 2 "GND") (pinfunction "2") (pintype "passive"))
    (pad "2" smd rect (at -2.975 4.955 90) (size 1.45 4.191) (layers "F.Cu" "F.Paste" "F.Mask")
      (net 2 "GND") (pinfunction "2") (pintype "passive"))
    (pad "2" smd rect (at 2.975 4.955 90) (size 1.45 4.191) (layers "B.Cu" "B.Paste" "B.Mask")
      (net 2 "GND") (pinfunction "2") (pintype "passive"))
  )
)
